FILE_TYPE = CONNECTIVITY;
{Allegro Design Entry HDL 17.2-2016 S081 (4005846) 1/11/2022}
"PAGE_NUMBER" = 114;
0"NC";
1"PWRGD_CHE_CPU0_DIMM1";
2"PWRGD_CHF_CPU0_DIMM2";
3"PWRGD_FAIL_CPU0_GH";
4"PWRGD_FAIL_CPU0_EF";
5"PWRGD_FAIL_CPU0_CD";
6"PWRGD_CHD_CPU0_DIMM2";
7"PWRGD_CHD_CPU0_DIMM1";
8"PWRGD_CHC_CPU0_DIMM1";
9"PWRGD_CHC_CPU0_DIMM2";
10"PWRGD_FAIL_CPU1_GH";
11"PWRGD_FAIL_CPU1_CD";
12"PWRGD_FAIL_CPU1_AB";
13"PWRGD_FAIL_CPU1_EF";
14"PWRGD_CHE_CPU1_DIMM1";
15"PWRGD_CHD_CPU1_DIMM2";
16"PWRGD_CHB_CPU0_DIMM1";
17"PWRGD_CHA_CPU0_DIMM2";
18"PWRGD_CHA_CPU0_DIMM1";
19"PWRGD_CHB_CPU0_DIMM2";
20"PWRGD_FAIL_CPU0_AB";
21"PWRGD_CHB_CPU1_DIMM2";
22"PWRGD_CHB_CPU1_DIMM1";
23"PWRGD_CHC_CPU1_DIMM1";
24"PWRGD_CHC_CPU1_DIMM2";
25"PWRGD_CHA_CPU1_DIMM1";
26"PWRGD_CHA_CPU1_DIMM2";
27"PWRGD_CHD_CPU1_DIMM1";
28"PWRGD_CHE_CPU1_DIMM2";
29"PWRGD_CHF_CPU1_DIMM1";
30"PWRGD_CHF_CPU1_DIMM2";
31"PWRGD_CHG_CPU1_DIMM1";
32"PWRGD_CHG_CPU1_DIMM2";
33"PWRGD_CHH_CPU1_DIMM1";
34"PWRGD_CHH_CPU1_DIMM2";
35"PWRGD_CHH_CPU0_DIMM2";
36"PWRGD_CHE_CPU0_DIMM2";
37"PWRGD_CHF_CPU0_DIMM1";
38"PWRGD_CHG_CPU0_DIMM2";
39"PWRGD_CHG_CPU0_DIMM1";
40"PWRGD_CHH_CPU0_DIMM1";
%"Q_RES"
"1","(-9375,4575)","0","pure_quanta","I17";
;
PART_NUMBER"CS03322FB03"
TOLERANCE"1%"
VALUE"33.2"
$LOCATION"R2735"
WATTAGE"1/16W"
PACK_TYPE"0402LF"
MATERIAL"CHIP"
CDS_LIB"pure_quanta"
CDS_LOCATION"R2735"
$SEC"1"
CDS_SEC"1";
"B"
$PN"2"3;
"A"
$PN"1"35;
%"Q_RES"
"1","(-9375,4625)","0","pure_quanta","I18";
;
PART_NUMBER"CS03322FB03"
WATTAGE"1/16W"
TOLERANCE"1%"
VALUE"33.2"
MATERIAL"CHIP"
PACK_TYPE"0402LF"
$LOCATION"R2734"
CDS_LIB"pure_quanta"
CDS_LOCATION"R2734"
$SEC"1"
CDS_SEC"1";
"B"
$PN"2"3;
"A"
$PN"1"40;
%"Q_RES"
"1","(-9375,4800)","0","pure_quanta","I19";
;
PART_NUMBER"CS03322FB03"
TOLERANCE"1%"
VALUE"33.2"
$LOCATION"R890"
WATTAGE"1/16W"
PACK_TYPE"0402LF"
MATERIAL"CHIP"
CDS_LIB"pure_quanta"
$LOCATION"R890"
CDS_LOCATION"R890"
$SEC"1"
CDS_SEC"1";
"B"
$PN"2"3;
"A"
$PN"1"38;
%"Q_RES"
"1","(-9375,4850)","0","pure_quanta","I20";
;
PART_NUMBER"CS03322FB03"
TOLERANCE"1%"
VALUE"33.2"
MATERIAL"CHIP"
WATTAGE"1/16W"
PACK_TYPE"0402LF"
$LOCATION"R889"
CDS_LIB"pure_quanta"
$LOCATION"R889"
CDS_LOCATION"R889"
$SEC"1"
CDS_SEC"1";
"B"
$PN"2"3;
"A"
$PN"1"39;
%"Q_RES"
"1","(-9375,5125)","0","pure_quanta","I21";
;
PART_NUMBER"CS03322FB03"
VALUE"33.2"
TOLERANCE"1%"
$LOCATION"R2733"
WATTAGE"1/16W"
PACK_TYPE"0402LF"
MATERIAL"CHIP"
CDS_LIB"pure_quanta"
CDS_LOCATION"R2733"
$SEC"1"
CDS_SEC"1";
"B"
$PN"2"4;
"A"
$PN"1"2;
%"Q_RES"
"1","(-9375,5175)","0","pure_quanta","I22";
;
PART_NUMBER"CS03322FB03"
VALUE"33.2"
WATTAGE"1/16W"
MATERIAL"CHIP"
PACK_TYPE"0402LF"
TOLERANCE"1%"
$LOCATION"R2732"
CDS_LIB"pure_quanta"
CDS_LOCATION"R2732"
$SEC"1"
CDS_SEC"1";
"B"
$PN"2"4;
"A"
$PN"1"37;
%"Q_RES"
"1","(-9375,5350)","0","pure_quanta","I23";
;
PART_NUMBER"CS03322FB03"
VALUE"33.2"
TOLERANCE"1%"
$LOCATION"R886"
WATTAGE"1/16W"
PACK_TYPE"0402LF"
MATERIAL"CHIP"
CDS_LIB"pure_quanta"
$LOCATION"R886"
CDS_LOCATION"R886"
$SEC"1"
CDS_SEC"1";
"B"
$PN"2"4;
"A"
$PN"1"36;
%"Q_RES"
"1","(-9375,5400)","0","pure_quanta","I24";
;
PART_NUMBER"CS03322FB03"
VALUE"33.2"
TOLERANCE"1%"
MATERIAL"CHIP"
PACK_TYPE"0402LF"
WATTAGE"1/16W"
$LOCATION"R885"
CDS_LIB"pure_quanta"
$LOCATION"R885"
CDS_LOCATION"R885"
$SEC"1"
CDS_SEC"1";
"B"
$PN"2"4;
"A"
$PN"1"1;
%"Q_RES"
"1","(-9375,5725)","0","pure_quanta","I25";
;
PART_NUMBER"CS03322FB03"
WATTAGE"1/16W"
PACK_TYPE"0402LF"
MATERIAL"CHIP"
VALUE"33.2"
TOLERANCE"1%"
$LOCATION"R2731"
CDS_LIB"pure_quanta"
CDS_LOCATION"R2731"
$SEC"1"
CDS_SEC"1";
"B"
$PN"2"5;
"A"
$PN"1"7;
%"Q_RES"
"1","(-9375,5675)","0","pure_quanta","I26";
;
PART_NUMBER"CS03322FB03"
VALUE"33.2"
TOLERANCE"1%"
$LOCATION"R884"
CDS_LIB"pure_quanta"
MATERIAL"CHIP"
PACK_TYPE"0402LF"
WATTAGE"1/16W"
$LOCATION"R884"
CDS_LOCATION"R884"
$SEC"1"
CDS_SEC"1";
"B"
$PN"2"5;
"A"
$PN"1"6;
%"Q_RES"
"1","(-9375,5900)","0","pure_quanta","I27";
;
PART_NUMBER"CS03322FB03"
VALUE"33.2"
TOLERANCE"1%"
$LOCATION"R2730"
CDS_LIB"pure_quanta"
MATERIAL"CHIP"
PACK_TYPE"0402LF"
WATTAGE"1/16W"
$LOCATION"R2730"
CDS_LOCATION"R2730"
$SEC"1"
CDS_SEC"1";
"B"
$PN"2"5;
"A"
$PN"1"9;
%"Q_RES"
"1","(-9375,5950)","0","pure_quanta","I28";
;
PART_NUMBER"CS03322FB03"
VALUE"33.2"
TOLERANCE"1%"
MATERIAL"CHIP"
WATTAGE"1/16W"
PACK_TYPE"0402LF"
$LOCATION"R2729"
CDS_LIB"pure_quanta"
CDS_LOCATION"R2729"
$SEC"1"
CDS_SEC"1";
"B"
$PN"2"5;
"A"
$PN"1"8;
%"Q_RES"
"1","(-9375,6225)","0","pure_quanta","I29";
;
PART_NUMBER"CS03322FB03"
VALUE"33.2"
TOLERANCE"1%"
$LOCATION"R880"
CDS_LIB"pure_quanta"
MATERIAL"CHIP"
PACK_TYPE"0402LF"
WATTAGE"1/16W"
$LOCATION"R880"
CDS_LOCATION"R880"
$SEC"1"
CDS_SEC"1";
"B"
$PN"2"20;
"A"
$PN"1"19;
%"Q_RES"
"1","(-9375,6275)","0","pure_quanta","I30";
;
PART_NUMBER"CS03322FB03"
VALUE"33.2"
TOLERANCE"1%"
MATERIAL"CHIP"
PACK_TYPE"0402LF"
WATTAGE"1/16W"
$LOCATION"R2728"
CDS_LIB"pure_quanta"
CDS_LOCATION"R2728"
$SEC"1"
CDS_SEC"1";
"B"
$PN"2"20;
"A"
$PN"1"16;
%"Q_RES"
"1","(-9375,6450)","0","pure_quanta","I31";
;
PART_NUMBER"CS03322FB03"
VALUE"33.2"
TOLERANCE"1%"
$LOCATION"R2727"
CDS_LIB"pure_quanta"
MATERIAL"CHIP"
PACK_TYPE"0402LF"
WATTAGE"1/16W"
$LOCATION"R2727"
CDS_LOCATION"R2727"
$SEC"1"
CDS_SEC"1";
"B"
$PN"2"20;
"A"
$PN"1"17;
%"Q_RES"
"1","(-9375,6500)","0","pure_quanta","I32";
;
PART_NUMBER"CS03322FB03"
WATTAGE"1/16W"
PACK_TYPE"0402LF"
MATERIAL"CHIP"
TOLERANCE"1%"
VALUE"33.2"
$LOCATION"R2726"
CDS_LIB"pure_quanta"
CDS_LOCATION"R2726"
$SEC"1"
CDS_SEC"1";
"B"
$PN"2"20;
"A"
$PN"1"18;
%"Q_RES"
"1","(-5700,4575)","0","pure_quanta","I57";
;
PART_NUMBER"CS03322FB03"
TOLERANCE"1%"
VALUE"33.2"
$LOCATION"R908"
WATTAGE"1/16W"
PACK_TYPE"0402LF"
MATERIAL"CHIP"
CDS_LIB"pure_quanta"
$LOCATION"R908"
CDS_LOCATION"R908"
$SEC"1"
CDS_SEC"1";
"B"
$PN"2"10;
"A"
$PN"1"34;
%"Q_RES"
"1","(-5700,4625)","0","pure_quanta","I58";
;
PART_NUMBER"CS03322FB03"
WATTAGE"1/16W"
TOLERANCE"1%"
VALUE"33.2"
PACK_TYPE"0402LF"
MATERIAL"CHIP"
$LOCATION"R907"
CDS_LIB"pure_quanta"
$LOCATION"R907"
CDS_LOCATION"R907"
$SEC"1"
CDS_SEC"1";
"B"
$PN"2"10;
"A"
$PN"1"33;
%"Q_RES"
"1","(-5700,4800)","0","pure_quanta","I59";
;
PART_NUMBER"CS03322FB03"
VALUE"33.2"
TOLERANCE"1%"
$LOCATION"R906"
WATTAGE"1/16W"
PACK_TYPE"0402LF"
MATERIAL"CHIP"
CDS_LIB"pure_quanta"
$LOCATION"R906"
CDS_LOCATION"R906"
$SEC"1"
CDS_SEC"1";
"B"
$PN"2"10;
"A"
$PN"1"32;
%"Q_RES"
"1","(-5700,4850)","0","pure_quanta","I60";
;
PART_NUMBER"CS03322FB03"
PACK_TYPE"0402LF"
MATERIAL"CHIP"
VALUE"33.2"
TOLERANCE"1%"
WATTAGE"1/16W"
$LOCATION"R905"
CDS_LIB"pure_quanta"
$LOCATION"R905"
CDS_LOCATION"R905"
$SEC"1"
CDS_SEC"1";
"B"
$PN"2"10;
"A"
$PN"1"31;
%"Q_RES"
"1","(-5700,5125)","0","pure_quanta","I61";
;
PART_NUMBER"CS03322FB03"
VALUE"33.2"
TOLERANCE"1%"
$LOCATION"R2736"
WATTAGE"1/16W"
PACK_TYPE"0402LF"
MATERIAL"CHIP"
CDS_LIB"pure_quanta"
CDS_LOCATION"R2736"
$SEC"1"
CDS_SEC"1";
"B"
$PN"2"13;
"A"
$PN"1"30;
%"Q_RES"
"1","(-5700,5175)","0","pure_quanta","I62";
;
PART_NUMBER"CS03322FB03"
WATTAGE"1/16W"
VALUE"33.2"
TOLERANCE"1%"
PACK_TYPE"0402LF"
MATERIAL"CHIP"
$LOCATION"R903"
CDS_LIB"pure_quanta"
$LOCATION"R903"
CDS_LOCATION"R903"
$SEC"1"
CDS_SEC"1";
"B"
$PN"2"13;
"A"
$PN"1"29;
%"Q_RES"
"1","(-5700,5350)","0","pure_quanta","I63";
;
PART_NUMBER"CS03322FB03"
VALUE"33.2"
TOLERANCE"1%"
$LOCATION"R902"
WATTAGE"1/16W"
PACK_TYPE"0402LF"
MATERIAL"CHIP"
CDS_LIB"pure_quanta"
$LOCATION"R902"
CDS_LOCATION"R902"
$SEC"1"
CDS_SEC"1";
"B"
$PN"2"13;
"A"
$PN"1"28;
%"Q_RES"
"1","(-5700,5400)","0","pure_quanta","I64";
;
PART_NUMBER"CS03322FB03"
WATTAGE"1/16W"
TOLERANCE"1%"
PACK_TYPE"0402LF"
VALUE"33.2"
MATERIAL"CHIP"
$LOCATION"R901"
CDS_LIB"pure_quanta"
$LOCATION"R901"
CDS_LOCATION"R901"
$SEC"1"
CDS_SEC"1";
"B"
$PN"2"13;
"A"
$PN"1"14;
%"Q_RES"
"1","(-5700,5725)","0","pure_quanta","I65";
;
PART_NUMBER"CS03322FB03"
VALUE"33.2"
TOLERANCE"1%"
WATTAGE"1/16W"
PACK_TYPE"0402LF"
MATERIAL"CHIP"
$LOCATION"R899"
CDS_LIB"pure_quanta"
$LOCATION"R899"
CDS_LOCATION"R899"
$SEC"1"
CDS_SEC"1";
"B"
$PN"2"11;
"A"
$PN"1"27;
%"Q_RES"
"1","(-5700,5675)","0","pure_quanta","I66";
;
PART_NUMBER"CS03322FB03"
TOLERANCE"1%"
VALUE"33.2"
$LOCATION"R900"
CDS_LIB"pure_quanta"
MATERIAL"CHIP"
PACK_TYPE"0402LF"
WATTAGE"1/16W"
$LOCATION"R900"
CDS_LOCATION"R900"
$SEC"1"
CDS_SEC"1";
"B"
$PN"2"11;
"A"
$PN"1"15;
%"Q_RES"
"1","(-5700,5950)","0","pure_quanta","I67";
;
PART_NUMBER"CS03322FB03"
MATERIAL"CHIP"
PACK_TYPE"0402LF"
WATTAGE"1/16W"
TOLERANCE"1%"
VALUE"33.2"
$LOCATION"R897"
CDS_LIB"pure_quanta"
$LOCATION"R897"
CDS_LOCATION"R897"
$SEC"1"
CDS_SEC"1";
"B"
$PN"2"11;
"A"
$PN"1"23;
%"Q_RES"
"1","(-5700,5900)","0","pure_quanta","I68";
;
PART_NUMBER"CS03322FB03"
VALUE"33.2"
TOLERANCE"1%"
$LOCATION"R898"
CDS_LIB"pure_quanta"
MATERIAL"CHIP"
PACK_TYPE"0402LF"
WATTAGE"1/16W"
$LOCATION"R898"
CDS_LOCATION"R898"
$SEC"1"
CDS_SEC"1";
"B"
$PN"2"11;
"A"
$PN"1"24;
%"Q_RES"
"1","(-5700,6225)","0","pure_quanta","I69";
;
PART_NUMBER"CS03322FB03"
VALUE"33.2"
TOLERANCE"1%"
$LOCATION"R896"
WATTAGE"1/16W"
PACK_TYPE"0402LF"
MATERIAL"CHIP"
CDS_LIB"pure_quanta"
$LOCATION"R896"
CDS_LOCATION"R896"
$SEC"1"
CDS_SEC"1";
"B"
$PN"2"12;
"A"
$PN"1"21;
%"Q_RES"
"1","(-5700,6275)","0","pure_quanta","I77";
;
PART_NUMBER"CS03322FB03"
WATTAGE"1/16W"
VALUE"33.2"
TOLERANCE"1%"
MATERIAL"CHIP"
PACK_TYPE"0402LF"
$LOCATION"R895"
CDS_LIB"pure_quanta"
$LOCATION"R895"
CDS_LOCATION"R895"
$SEC"1"
CDS_SEC"1";
"B"
$PN"2"12;
"A"
$PN"1"22;
%"Q_RES"
"1","(-5700,6450)","0","pure_quanta","I78";
;
PART_NUMBER"CS03322FB03"
TOLERANCE"1%"
VALUE"33.2"
$LOCATION"R894"
CDS_LIB"pure_quanta"
MATERIAL"CHIP"
PACK_TYPE"0402LF"
WATTAGE"1/16W"
$LOCATION"R894"
CDS_LOCATION"R894"
$SEC"1"
CDS_SEC"1";
"B"
$PN"2"12;
"A"
$PN"1"26;
%"Q_RES"
"1","(-5700,6500)","0","pure_quanta","I79";
;
PART_NUMBER"CS03322FB03"
TOLERANCE"1%"
VALUE"33.2"
PACK_TYPE"0402LF"
MATERIAL"CHIP"
WATTAGE"1/16W"
$LOCATION"R893"
CDS_LIB"pure_quanta"
$LOCATION"R893"
CDS_LOCATION"R893"
$SEC"1"
CDS_SEC"1";
"B"
$PN"2"12;
"A"
$PN"1"25;
END.
